# T6G (Grand Teton) — schematic netlist excerpt (pin names and nets, part order shuffled) for the footprints in the layout excerpt that follows; sources: Cadence DE-HDL packaged netlist, KiCad conversion of 04192023_DAF0TMB3IC0_F0TG_MB_C_brd_V02_OCP.brd

R3338  Q_RES  0 5% CHIP  pkg 0402LF  page 233 : A = CLK_100M_GPU_FPGA_DN_R ; B = CLK_100M_GPU_FPGA_DN
R8184  Q_RES  1K 1% CHIP  pkg 0402LF  page 210 : A = PVDD18_S5_P1 ; B = PVDDCR_CPU0_P1_RESET_N_R
R1029  Q_RES  10K 1% CHIP  pkg 0201LF  page 287 : A = GPIO3_RT_CPU0_P1 ; B = GND

(kicad_pcb
	(version 20260206)
	(generator "pcbnew")
	(generator_version "10.0")
	(general
		(thickness 1.6)
		(legacy_teardrops no)
	)
	(paper "A4")
	(title_block
		(title "04192023_DAF0TMB3IC0_F0TG_MB_C_brd_V02_OCP.brd")
		(comment 1 "Grand Teton / footprints 4598-4600 of 8354")
	)
	(layers
		(0 "F.Cu" signal "TOP")
		(4 "In1.Cu" signal "GND")
		(6 "In2.Cu" signal "IN1")
		(8 "In3.Cu" signal "GND1")
		(10 "In4.Cu" signal "IN2")
		(12 "In5.Cu" signal "GND2")
		(14 "In6.Cu" signal "IN3")
		(16 "In7.Cu" signal "GND3")
		(18 "In8.Cu" signal "VCC")
		(20 "In9.Cu" signal "VCC1")
		(22 "In10.Cu" signal "GND4")
		(24 "In11.Cu" signal "IN4")
		(26 "In12.Cu" signal "GND5")
		(28 "In13.Cu" signal "IN5")
		(30 "In14.Cu" signal "GND6")
		(32 "In15.Cu" signal "IN6")
		(34 "In16.Cu" signal "GND7")
		(2 "B.Cu" signal "BOTTOM")
		(9 "F.Adhes" user "F.Adhesive")
		(11 "B.Adhes" user "B.Adhesive")
		(13 "F.Paste" user "Package Geometry/Pastemask Top")
		(15 "B.Paste" user "Package Geometry/Pastemask Bottom")
		(5 "F.SilkS" user "Ref Des/Silkscreen Top")
		(7 "B.SilkS" user "Ref Des/Silkscreen Bottom")
		(1 "F.Mask" user "Board Geometry/Soldermask Top")
		(3 "B.Mask" user "Board Geometry/Soldermask Bottom")
		(17 "Dwgs.User" user "User.Drawings")
		(19 "Cmts.User" user "User.Comments")
		(21 "Eco1.User" user "User.Eco1")
		(23 "Eco2.User" user "User.Eco2")
		(25 "Edge.Cuts" user "Board Geometry/Outline")
		(27 "Margin" user)
		(31 "F.CrtYd" user "Package Geometry/Place Bound Top")
		(29 "B.CrtYd" user "Package Geometry/Place Bound Bottom")
		(35 "F.Fab" user "Ref Des/Assembly Top")
		(33 "B.Fab" user "Ref Des/Assembly Bottom")
	)
	(footprint ""
		(layer "F.Cu")
		(at 90.209878 -143.86941)
		(property "Reference" "R8184"
			(at 0 0 0)
			(layer "F.SilkS")
			(hide yes)
			(effects
				(font
					(size 1.27 1.27)
				)
			)
		)
		(property "Value" ""
			(at 0 0 0)
			(layer "F.Fab")
			(effects
				(font
					(size 1.27 1.27)
				)
			)
		)
		(duplicate_pad_numbers_are_jumpers no)
		(fp_line
			(start -0.7874 -0.4064)
			(end 0.7874 -0.4064)
			(stroke
				(width 0.1524)
				(type default)
			)
			(layer "F.SilkS")
		)
		(fp_line
			(start -0.7874 0.4064)
			(end -0.7874 -0.4064)
			(stroke
				(width 0.1524)
				(type default)
			)
			(layer "F.SilkS")
		)
		(fp_line
			(start 0.7874 -0.4064)
			(end 0.7874 0.4064)
			(stroke
				(width 0.1524)
				(type default)
			)
			(layer "F.SilkS")
		)
		(fp_line
			(start 0.7874 0.4064)
			(end -0.7874 0.4064)
			(stroke
				(width 0.1524)
				(type default)
			)
			(layer "F.SilkS")
		)
		(fp_line
			(start -0.67945 -0.305054)
			(end -0.12065 -0.305054)
			(stroke
				(width 0.1)
				(type default)
			)
			(layer "F.Fab")
		)
		(fp_line
			(start -0.67945 0.3048)
			(end -0.67945 -0.305054)
			(stroke
				(width 0.1)
				(type default)
			)
			(layer "F.Fab")
		)
		(fp_line
			(start -0.12065 -0.305054)
			(end -0.12065 -0.2794)
			(stroke
				(width 0.1)
				(type default)
			)
			(layer "F.Fab")
		)
		(fp_line
			(start -0.12065 -0.2794)
			(end 0.12065 -0.2794)
			(stroke
				(width 0.1)
				(type default)
			)
			(layer "F.Fab")
		)
		(fp_line
			(start -0.12065 0.2794)
			(end -0.12065 0.3048)
			(stroke
				(width 0.1)
				(type default)
			)
			(layer "F.Fab")
		)
		(fp_line
			(start -0.12065 0.3048)
			(end -0.67945 0.3048)
			(stroke
				(width 0.1)
				(type default)
			)
			(layer "F.Fab")
		)
		(fp_line
			(start 0.120396 0.2794)
			(end -0.12065 0.2794)
			(stroke
				(width 0.1)
				(type default)
			)
			(layer "F.Fab")
		)
		(fp_line
			(start 0.120396 0.3048)
			(end 0.120396 0.2794)
			(stroke
				(width 0.1)
				(type default)
			)
			(layer "F.Fab")
		)
		(fp_line
			(start 0.12065 -0.3048)
			(end 0.67945 -0.3048)
			(stroke
				(width 0.1)
				(type default)
			)
			(layer "F.Fab")
		)
		(fp_line
			(start 0.12065 -0.2794)
			(end 0.12065 -0.3048)
			(stroke
				(width 0.1)
				(type default)
			)
			(layer "F.Fab")
		)
		(fp_line
			(start 0.67945 -0.3048)
			(end 0.67945 0.3048)
			(stroke
				(width 0.1)
				(type default)
			)
			(layer "F.Fab")
		)
		(fp_line
			(start 0.67945 0.3048)
			(end 0.120396 0.3048)
			(stroke
				(width 0.1)
				(type default)
			)
			(layer "F.Fab")
		)
		(pad "1" smd circle
			(at -0.40005 0)
			(size 0 0)
			(layers "F.Cu" "F.Mask" "F.Paste")
			(net "PVDD18_S5_P1")
		)
		(pad "2" smd circle
			(at 0.40005 0)
			(size 0 0)
			(layers "F.Cu" "F.Mask" "F.Paste")
			(net "PVDDCR_CPU0_P1_RESET_N_R")
		)
	)
	(footprint ""
		(layer "F.Cu")
		(at 18.702782 -137.976102)
		(property "Reference" "R3338"
			(at 0 0 0)
			(layer "F.SilkS")
			(hide yes)
			(effects
				(font
					(size 1.27 1.27)
				)
			)
		)
		(property "Value" ""
			(at 0 0 0)
			(layer "F.Fab")
			(effects
				(font
					(size 1.27 1.27)
				)
			)
		)
		(duplicate_pad_numbers_are_jumpers no)
		(fp_line
			(start -0.7874 -0.4064)
			(end 0.7874 -0.4064)
			(stroke
				(width 0.1524)
				(type default)
			)
			(layer "F.SilkS")
		)
		(fp_line
			(start -0.7874 0.4064)
			(end -0.7874 -0.4064)
			(stroke
				(width 0.1524)
				(type default)
			)
			(layer "F.SilkS")
		)
		(fp_line
			(start 0.7874 -0.4064)
			(end 0.7874 0.4064)
			(stroke
				(width 0.1524)
				(type default)
			)
			(layer "F.SilkS")
		)
		(fp_line
			(start 0.7874 0.4064)
			(end -0.7874 0.4064)
			(stroke
				(width 0.1524)
				(type default)
			)
			(layer "F.SilkS")
		)
		(fp_line
			(start -0.67945 -0.305054)
			(end -0.12065 -0.305054)
			(stroke
				(width 0.1)
				(type default)
			)
			(layer "F.Fab")
		)
		(fp_line
			(start -0.67945 0.3048)
			(end -0.67945 -0.305054)
			(stroke
				(width 0.1)
				(type default)
			)
			(layer "F.Fab")
		)
		(fp_line
			(start -0.12065 -0.305054)
			(end -0.12065 -0.2794)
			(stroke
				(width 0.1)
				(type default)
			)
			(layer "F.Fab")
		)
		(fp_line
			(start -0.12065 -0.2794)
			(end 0.12065 -0.2794)
			(stroke
				(width 0.1)
				(type default)
			)
			(layer "F.Fab")
		)
		(fp_line
			(start -0.12065 0.2794)
			(end -0.12065 0.3048)
			(stroke
				(width 0.1)
				(type default)
			)
			(layer "F.Fab")
		)
		(fp_line
			(start -0.12065 0.3048)
			(end -0.67945 0.3048)
			(stroke
				(width 0.1)
				(type default)
			)
			(layer "F.Fab")
		)
		(fp_line
			(start 0.120396 0.2794)
			(end -0.12065 0.2794)
			(stroke
				(width 0.1)
				(type default)
			)
			(layer "F.Fab")
		)
		(fp_line
			(start 0.120396 0.3048)
			(end 0.120396 0.2794)
			(stroke
				(width 0.1)
				(type default)
			)
			(layer "F.Fab")
		)
		(fp_line
			(start 0.12065 -0.3048)
			(end 0.67945 -0.3048)
			(stroke
				(width 0.1)
				(type default)
			)
			(layer "F.Fab")
		)
		(fp_line
			(start 0.12065 -0.2794)
			(end 0.12065 -0.3048)
			(stroke
				(width 0.1)
				(type default)
			)
			(layer "F.Fab")
		)
		(fp_line
			(start 0.67945 -0.3048)
			(end 0.67945 0.3048)
			(stroke
				(width 0.1)
				(type default)
			)
			(layer "F.Fab")
		)
		(fp_line
			(start 0.67945 0.3048)
			(end 0.120396 0.3048)
			(stroke
				(width 0.1)
				(type default)
			)
			(layer "F.Fab")
		)
		(pad "1" smd circle
			(at -0.40005 0)
			(size 0 0)
			(layers "F.Cu" "F.Mask" "F.Paste")
			(net "CLK_100M_GPU_FPGA_DN_R")
		)
		(pad "2" smd circle
			(at 0.40005 0)
			(size 0 0)
			(layers "F.Cu" "F.Mask" "F.Paste")
			(net "CLK_100M_GPU_FPGA_DN")
		)
	)
	(footprint ""
		(layer "F.Cu")
		(at 331.793342 -393.04468)
		(property "Reference" "R1029"
			(at 0 0 0)
			(layer "F.SilkS")
			(hide yes)
			(effects
				(font
					(size 1.27 1.27)
				)
			)
		)
		(property "Value" ""
			(at 0 0 0)
			(layer "F.Fab")
			(effects
				(font
					(size 1.27 1.27)
				)
			)
		)
		(duplicate_pad_numbers_are_jumpers no)
		(fp_line
			(start -0.32512 -0.175006)
			(end 0.32512 -0.175006)
			(stroke
				(width 0.1)
				(type default)
			)
			(layer "F.Fab")
		)
		(fp_line
			(start -0.32512 0.175006)
			(end -0.32512 -0.175006)
			(stroke
				(width 0.1)
				(type default)
			)
			(layer "F.Fab")
		)
		(fp_line
			(start 0.32512 -0.175006)
			(end 0.32512 0.175006)
			(stroke
				(width 0.1)
				(type default)
			)
			(layer "F.Fab")
		)
		(fp_line
			(start 0.32512 0.175006)
			(end -0.32512 0.175006)
			(stroke
				(width 0.1)
				(type default)
			)
			(layer "F.Fab")
		)
		(pad "1" smd rect
			(at -0.2667 0)
			(size 0.3048 0.381)
			(layers "F.Cu" "F.Mask" "F.Paste")
			(net "GPIO3_RT_CPU0_P1")
		)
		(pad "2" smd rect
			(at 0.2667 0 180)
			(size 0.3048 0.381)
			(layers "F.Cu" "F.Mask" "F.Paste")
			(net "GND")
		)
	)
)
